# T6G (Grand Teton) — schematic netlist excerpt (pin names and nets, part order shuffled) for the footprints in the layout excerpt that follows; sources: Cadence DE-HDL packaged netlist, KiCad conversion of 04192023_DAF0TMB3IC0_F0TG_MB_C_brd_V02_OCP.brd

J24  SCONN288_DDR506112002KQ  IO  pkg DDR288S_1-1VXC  page 98
  VIN_BULK0  = P12V_MEM_CPU1
  RFU0  = NC
  VIN_MGMT  = P3V3_AUX
  HSCL  = I3C_SPD_DDRA_CPU1_SCL
  HSDA  = I3C_SPD_DDRA_CPU1_SDA
  VSS0  = GND
  DQ0_A  = M_A_CPU1_SA_DQ<0>
  VSS1  = GND
  DQ1_A  = M_A_CPU1_SA_DQ<1>
  VSS2  = GND
  DQS0_A_T  = M_A_CPU1_SA_DQS_DP<0>
  DQS0_A_C  = M_A_CPU1_SA_DQS_DN<0>
  VSS3  = GND
  DQ4_A  = M_A_CPU1_SA_DQ<4>
  VSS4  = GND
  DQ5_A  = M_A_CPU1_SA_DQ<5>
  VSS5  = GND
  DQ8_A  = M_A_CPU1_SA_DQ<8>
  VSS6  = GND
  DQ9_A  = M_A_CPU1_SA_DQ<9>
  VSS7  = GND
  DQS1_A_T  = M_A_CPU1_SA_DQS_DP<1>
  DQS1_A_C  = M_A_CPU1_SA_DQS_DN<1>
  VSS8  = GND
  DQ12_A  = M_A_CPU1_SA_DQ<12>
  VSS9  = GND
  DQ13_A  = M_A_CPU1_SA_DQ<13>
  VSS10  = GND
  DQ16_A  = M_A_CPU1_SA_DQ<16>
  VSS11  = GND
  DQ17_A  = M_A_CPU1_SA_DQ<17>
  VSS12  = GND
  DQS2_A_T  = M_A_CPU1_SA_DQS_DP<2>
  DQS2_A_C  = M_A_CPU1_SA_DQS_DN<2>
  VSS13  = GND
  DQ20_A  = M_A_CPU1_SA_DQ<20>
  VSS14  = GND
  DQ21_A  = M_A_CPU1_SA_DQ<21>
  VSS15  = GND
  DQ24_A  = M_A_CPU1_SA_DQ<24>
  VSS16  = GND
  DQ25_A  = M_A_CPU1_SA_DQ<25>
  VSS17  = GND
  DQS3_A_T  = M_A_CPU1_SA_DQS_DP<3>
  DQS3_A_C  = M_A_CPU1_SA_DQS_DN<3>
  VSS18  = GND
  DQ28_A  = M_A_CPU1_SA_DQ<28>
  VSS19  = GND
  DQ29_A  = M_A_CPU1_SA_DQ<29>
  VSS20  = GND
  CB0_A  = M_A_CPU1_SA_CB<0>
  VSS21  = GND
  CB1_A  = M_A_CPU1_SA_CB<1>
  VSS22  = GND
  DQS4_A_T  = M_A_CPU1_SA_DQS_DP<4>
  DQS4_A_C  = M_A_CPU1_SA_DQS_DN<4>
  VSS23  = GND
  CB4_A  = M_A_CPU1_SA_CB<4>
  VSS24  = GND
  CB5_A  = M_A_CPU1_SA_CB<5>
  VSS25  = GND
  ALERT_N  = M_A_CPU1_ALERT_N
  VSS26  = GND
  CS0_A_N  = M_A_CPU1_SA_CS_N<0>
  VSS27  = GND
  CA0_A  = M_A_CPU1_SA_CA<0>
  VSS28  = GND
  CA2_A  = M_A_CPU1_SA_CA<2>
  VSS29  = GND
  CA4_A  = M_A_CPU1_SA_CA<4>
  VSS30  = GND
  CA6_A  = M_A_CPU1_SA_CA<6>
  VSS31  = GND
  PAR_A  = M_A_CPU1_SA_PAR
  VSS32  = GND
  CA0_B  = M_A_CPU1_SB_CA<0>
  VSS33  = GND
  CA2_B  = M_A_CPU1_SB_CA<2>
  VSS34  = GND
  CA4_B  = M_A_CPU1_SB_CA<4>
  VSS35  = GND
  CA6_B  = M_A_CPU1_SB_CA<6>
  VSS36  = GND
  CS0_B_N  = M_A_CPU1_SB_CS_N<0>
  VSS37  = GND
  \lbd||rsp_a_n\  = M_A_CPU1_SA_RSP<0>
  \lbs||rsp_b_n\  = M_A_CPU1_SB_RSP<0>
  VSS38  = GND
  CB4_B  = M_A_CPU1_SB_CB<4>
  VSS39  = GND
  CB5_B  = M_A_CPU1_SB_CB<5>
  VSS40  = GND
  \dqs9_b_t||tdqs9_b_t||dbi4_b_n\  = M_A_CPU1_SB_DQS_DP<9>
  \dqs9_b_c||tdqs9_b_c\  = M_A_CPU1_SB_DQS_DN<9>
  VSS41  = GND
  CB0_B  = M_A_CPU1_SB_CB<0>
  VSS42  = GND
  CB1_B  = M_A_CPU1_SB_CB<1>
  VSS43  = GND
  DQ0_B  = M_A_CPU1_SB_DQ<0>
  VSS44  = GND
  DQ1_B  = M_A_CPU1_SB_DQ<1>
  VSS45  = GND
  DQS0_B_T  = M_A_CPU1_SB_DQS_DP<0>
  DQS0_B_C  = M_A_CPU1_SB_DQS_DN<0>
  VSS46  = GND
  DQ4_B  = M_A_CPU1_SB_DQ<4>
  VSS47  = GND
  DQ5_B  = M_A_CPU1_SB_DQ<5>
  VSS48  = GND
  DQ8_B  = M_A_CPU1_SB_DQ<8>
  VSS49  = GND
  DQ9_B  = M_A_CPU1_SB_DQ<9>
  VSS50  = GND
  DQS1_B_T  = M_A_CPU1_SB_DQS_DP<1>
  DQS1_B_C  = M_A_CPU1_SB_DQS_DN<1>
  VSS51  = GND
  DQ12_B  = M_A_CPU1_SB_DQ<12>
  VSS52  = GND
  DQ13_B  = M_A_CPU1_SB_DQ<13>
  VSS53  = GND
  DQ16_B  = M_A_CPU1_SB_DQ<16>
  VSS54  = GND
  DQ17_B  = M_A_CPU1_SB_DQ<17>
  VSS55  = GND
  DQS2_B_T  = M_A_CPU1_SB_DQS_DP<2>
  DQS2_B_C  = M_A_CPU1_SB_DQS_DN<2>
  VSS56  = GND
  DQ20_B  = M_A_CPU1_SB_DQ<20>
  VSS57  = GND
  DQ21_B  = M_A_CPU1_SB_DQ<21>
  VSS58  = GND
  DQ24_B  = M_A_CPU1_SB_DQ<24>
  VSS59  = GND
  DQ25_B  = M_A_CPU1_SB_DQ<25>
  VSS60  = GND
  DQS3_B_T  = M_A_CPU1_SB_DQS_DP<3>
  DQS3_B_C  = M_A_CPU1_SB_DQS_DN<3>
  VSS61  = GND
  DQ28_B  = M_A_CPU1_SB_DQ<28>
  VSS62  = GND
  DQ29_B  = M_A_CPU1_SB_DQ<29>
  VSS63  = GND
  RFU1  = NC
  VIN_BULK1  = P12V_MEM_CPU1
  VIN_BULK2  = P12V_MEM_CPU1
  \pwr_good||fail_n\  = PWRGD_CHA_CPU1_DIMM0
  HAS  = PD_CHA_CPU1_DIMM0_SAA
  RFU2  = NC
  RFU3  = NC
  VSS64  = GND
  DQ2_A  = M_A_CPU1_SA_DQ<2>
  VSS65  = GND
  DQ3_A  = M_A_CPU1_SA_DQ<3>
  VSS66  = GND
  \dqs5_a_c||tdqs5_a_c||dqs5_a_t||tdqs5_a_t\  = M_A_CPU1_SA_DQS_DN<5>
  \dqs5_a_t||tdqs5_a_t\  = M_A_CPU1_SA_DQS_DP<5>
  VSS67  = GND
  DQ6_A  = M_A_CPU1_SA_DQ<6>
  VSS68  = GND
  DQ7_A  = M_A_CPU1_SA_DQ<7>
  VSS69  = GND
  DQ10_A  = M_A_CPU1_SA_DQ<10>
  VSS70  = GND
  DQ11_A  = M_A_CPU1_SA_DQ<11>
  VSS71  = GND
  \dqs6_a_c||tdqs6_a_c||dqs6_a_t||tdqs6_a_t\  = M_A_CPU1_SA_DQS_DN<6>
  \dqs6_a_t||tdqs6_a_t\  = M_A_CPU1_SA_DQS_DP<6>
  VSS72  = GND
  DQ14_A  = M_A_CPU1_SA_DQ<14>
  VSS73  = GND
  DQ15_A  = M_A_CPU1_SA_DQ<15>
  VSS74  = GND
  DQ18_A  = M_A_CPU1_SA_DQ<18>
  VSS75  = GND
  DQ19_A  = M_A_CPU1_SA_DQ<19>
  VSS76  = GND
  \dqs7_a_c||tdqs7_a_c\  = M_A_CPU1_SA_DQS_DN<7>
  \dqs7_a_t||tdqs7_a_t\  = M_A_CPU1_SA_DQS_DP<7>
  VSS77  = GND
  DQ22_A  = M_A_CPU1_SA_DQ<22>
  VSS78  = GND
  DQ23_A  = M_A_CPU1_SA_DQ<23>
  VSS79  = GND
  DQ26_A  = M_A_CPU1_SA_DQ<26>
  VSS80  = GND
  DQ27_A  = M_A_CPU1_SA_DQ<27>
  VSS81  = GND
  \dqs8_a_c||tdqs8_a_c\  = M_A_CPU1_SA_DQS_DN<8>
  \dqs8_a_t||tdqs8_a_t\  = M_A_CPU1_SA_DQS_DP<8>
  VSS82  = GND
  DQ30_A  = M_A_CPU1_SA_DQ<30>
  VSS83  = GND
  DQ31_A  = M_A_CPU1_SA_DQ<31>
  VSS84  = GND
  CB2_A  = M_A_CPU1_SA_CB<2>
  VSS85  = GND
  CB3_A  = M_A_CPU1_SA_CB<3>
  VSS86  = GND
  \dqs9_a_c||tdqs9_a_c\  = M_A_CPU1_SA_DQS_DN<9>
  \dqs9_a_t||tdqs9_a_t\  = M_A_CPU1_SA_DQS_DP<9>
  VSS87  = GND
  CB6_A  = M_A_CPU1_SA_CB<6>
  VSS88  = GND
  CB7_A  = M_A_CPU1_SA_CB<7>
  VSS89  = GND
  RESET_N  = M_A_CPU1_RESET_N
  VSS90  = GND
  CS1_A_N  = M_A_CPU1_SA_CS_N<1>
  VSS91  = GND
  CA1_A  = M_A_CPU1_SA_CA<1>
  VSS92  = GND
  CA3_A  = M_A_CPU1_SA_CA<3>
  VSS93  = GND
  CA5_A  = M_A_CPU1_SA_CA<5>
  VSS94  = GND
  CK_T  = M_A_CPU1_CLK_DP<0>
  CK_C  = M_A_CPU1_CLK_DN<0>
  VSS95  = GND
  RFU4  = NC
  CA1_B  = M_A_CPU1_SB_CA<1>
  VSS96  = GND
  CA3_B  = M_A_CPU1_SB_CA<3>
  VSS97  = GND
  CA5_B  = M_A_CPU1_SB_CA<5>
  VSS98  = GND
  PAR_B  = M_A_CPU1_SB_PAR
  VSS99  = GND
  CS1_B_N  = M_A_CPU1_SB_CS_N<1>
  VSS100  = GND
  RFU5  = NC
  RFU6  = NC
  VSS101  = GND
  CB6_B  = M_A_CPU1_SB_CB<6>
  VSS102  = GND
  CB7_B  = M_A_CPU1_SB_CB<7>
  VSS103  = GND
  DQS4_B_C  = M_A_CPU1_SB_DQS_DN<4>
  DQS4_B_T  = M_A_CPU1_SB_DQS_DP<4>
  VSS104  = GND
  CB2_B  = M_A_CPU1_SB_CB<2>
  VSS105  = GND
  CB3_B  = M_A_CPU1_SB_CB<3>
  VSS106  = GND
  DQ2_B  = M_A_CPU1_SB_DQ<2>
  VSS107  = GND
  DQ3_B  = M_A_CPU1_SB_DQ<3>
  VSS108  = GND
  \dqs5_b_c||tdqs5_b_c\  = M_A_CPU1_SB_DQS_DN<5>
  \dqs5_b_t||tdqs5_b_t\  = M_A_CPU1_SB_DQS_DP<5>
  VSS109  = GND
  DQ6_B  = M_A_CPU1_SB_DQ<6>
  VSS110  = GND
  DQ7_B  = M_A_CPU1_SB_DQ<7>
  VSS111  = GND
  DQ10_B  = M_A_CPU1_SB_DQ<10>
  VSS112  = GND
  DQ11_B  = M_A_CPU1_SB_DQ<11>
  VSS113  = GND
  \dqs6_b_c||tdqs6_b_c\  = M_A_CPU1_SB_DQS_DN<6>
  \dqs6_b_t||tdqs6_b_t\  = M_A_CPU1_SB_DQS_DP<6>
  VSS114  = GND
  DQ14_B  = M_A_CPU1_SB_DQ<14>
  VSS115  = GND
  DQ15_B  = M_A_CPU1_SB_DQ<15>
  VSS116  = GND
  DQ18_B  = M_A_CPU1_SB_DQ<18>
  VSS117  = GND
  DQ19_B  = M_A_CPU1_SB_DQ<19>
  VSS118  = GND
  \dqs7_b_c||tdqs7_b_c\  = M_A_CPU1_SB_DQS_DN<7>
  \dqs7_b_t||tdqs7_b_t\  = M_A_CPU1_SB_DQS_DP<7>
  VSS119  = GND
  DQ22_B  = M_A_CPU1_SB_DQ<22>
  VSS120  = GND
  DQ23_B  = M_A_CPU1_SB_DQ<23>
  VSS121  = GND
  DQ26_B  = M_A_CPU1_SB_DQ<26>
  VSS122  = GND
  DQ27_B  = M_A_CPU1_SB_DQ<27>
  VSS123  = GND
  \dqs8_b_c||tdqs8_b_c\  = M_A_CPU1_SB_DQS_DN<8>
  \dqs8_b_t||tdqs8_b_t\  = M_A_CPU1_SB_DQS_DP<8>
  VSS124  = GND
  DQ30_B  = M_A_CPU1_SB_DQ<30>
  VSS125  = GND
  DQ31_B  = M_A_CPU1_SB_DQ<31>
  VSS126  = GND
  G1  = GND
  G2  = GND
  G3  = GND

(kicad_pcb
	(version 20260206)
	(generator "pcbnew")
	(generator_version "10.0")
	(general
		(thickness 1.6)
		(legacy_teardrops no)
	)
	(paper "A4")
	(title_block
		(title "04192023_DAF0TMB3IC0_F0TG_MB_C_brd_V02_OCP.brd")
		(comment 1 "Grand Teton / footprint 2100 of 8354 (J24), pads 93-138 of 291")
	)
	(layers
		(0 "F.Cu" signal "TOP")
		(4 "In1.Cu" signal "GND")
		(6 "In2.Cu" signal "IN1")
		(8 "In3.Cu" signal "GND1")
		(10 "In4.Cu" signal "IN2")
		(12 "In5.Cu" signal "GND2")
		(14 "In6.Cu" signal "IN3")
		(16 "In7.Cu" signal "GND3")
		(18 "In8.Cu" signal "VCC")
		(20 "In9.Cu" signal "VCC1")
		(22 "In10.Cu" signal "GND4")
		(24 "In11.Cu" signal "IN4")
		(26 "In12.Cu" signal "GND5")
		(28 "In13.Cu" signal "IN5")
		(30 "In14.Cu" signal "GND6")
		(32 "In15.Cu" signal "IN6")
		(34 "In16.Cu" signal "GND7")
		(2 "B.Cu" signal "BOTTOM")
		(9 "F.Adhes" user "F.Adhesive")
		(11 "B.Adhes" user "B.Adhesive")
		(13 "F.Paste" user "Package Geometry/Pastemask Top")
		(15 "B.Paste" user "Package Geometry/Pastemask Bottom")
		(5 "F.SilkS" user "Ref Des/Silkscreen Top")
		(7 "B.SilkS" user "Ref Des/Silkscreen Bottom")
		(1 "F.Mask" user "Board Geometry/Soldermask Top")
		(3 "B.Mask" user "Board Geometry/Soldermask Bottom")
		(17 "Dwgs.User" user "User.Drawings")
		(19 "Cmts.User" user "User.Comments")
		(21 "Eco1.User" user "User.Eco1")
		(23 "Eco2.User" user "User.Eco2")
		(25 "Edge.Cuts" user "Board Geometry/Outline")
		(27 "Margin" user)
		(31 "F.CrtYd" user "Package Geometry/Place Bound Top")
		(29 "B.CrtYd" user "Package Geometry/Place Bound Bottom")
		(35 "F.Fab" user "Ref Des/Assembly Top")
		(33 "B.Fab" user "Ref Des/Assembly Bottom")
	)
	(footprint ""
		(layer "F.Cu")
		(at 57.378092 -255.560322 180)
		(property "Reference" "J24"
			(at 1.914906 -84.58708 0)
			(unlocked yes)
			(layer "F.SilkS")
			(effects
				(font
					(size 0.7874 0.5842)
					(thickness 0.1524)
				)
			)
		)
		(property "Value" ""
			(at 0 0 180)
			(layer "F.Fab")
			(effects
				(font
					(size 1.27 1.27)
				)
			)
		)
		(duplicate_pad_numbers_are_jumpers no)
		(pad "93" smd rect
			(at -2.050034 19.975068 90)
			(size 0.519938 1.4986)
			(layers "F.Cu" "F.Mask" "F.Paste")
			(net "M_A_CPU1_SB_DQS_DP<9>")
		)
		(pad "94" smd rect
			(at -2.050034 20.824952 90)
			(size 0.519938 1.4986)
			(layers "F.Cu" "F.Mask" "F.Paste")
			(net "M_A_CPU1_SB_DQS_DN<9>")
		)
		(pad "95" smd rect
			(at -2.050034 21.67509 90)
			(size 0.519938 1.4986)
			(layers "F.Cu" "F.Mask" "F.Paste")
			(net "GND")
		)
		(pad "96" smd rect
			(at -2.050034 22.524974 90)
			(size 0.519938 1.4986)
			(layers "F.Cu" "F.Mask" "F.Paste")
			(net "M_A_CPU1_SB_CB<0>")
		)
		(pad "97" smd rect
			(at -2.050034 23.375112 90)
			(size 0.519938 1.4986)
			(layers "F.Cu" "F.Mask" "F.Paste")
			(net "GND")
		)
		(pad "98" smd rect
			(at -2.050034 24.224996 90)
			(size 0.519938 1.4986)
			(layers "F.Cu" "F.Mask" "F.Paste")
			(net "M_A_CPU1_SB_CB<1>")
		)
		(pad "99" smd rect
			(at -2.050034 25.07488 90)
			(size 0.519938 1.4986)
			(layers "F.Cu" "F.Mask" "F.Paste")
			(net "GND")
		)
		(pad "100" smd rect
			(at -2.050034 25.925018 90)
			(size 0.519938 1.4986)
			(layers "F.Cu" "F.Mask" "F.Paste")
			(net "M_A_CPU1_SB_DQ<0>")
		)
		(pad "101" smd rect
			(at -2.050034 26.774902 90)
			(size 0.519938 1.4986)
			(layers "F.Cu" "F.Mask" "F.Paste")
			(net "GND")
		)
		(pad "102" smd rect
			(at -2.050034 27.62504 90)
			(size 0.519938 1.4986)
			(layers "F.Cu" "F.Mask" "F.Paste")
			(net "M_A_CPU1_SB_DQ<1>")
		)
		(pad "103" smd rect
			(at -2.050034 28.474924 90)
			(size 0.519938 1.4986)
			(layers "F.Cu" "F.Mask" "F.Paste")
			(net "GND")
		)
		(pad "104" smd rect
			(at -2.050034 29.325062 90)
			(size 0.519938 1.4986)
			(layers "F.Cu" "F.Mask" "F.Paste")
			(net "M_A_CPU1_SB_DQS_DP<0>")
		)
		(pad "105" smd rect
			(at -2.050034 30.174946 90)
			(size 0.519938 1.4986)
			(layers "F.Cu" "F.Mask" "F.Paste")
			(net "M_A_CPU1_SB_DQS_DN<0>")
		)
		(pad "106" smd rect
			(at -2.050034 31.025084 90)
			(size 0.519938 1.4986)
			(layers "F.Cu" "F.Mask" "F.Paste")
			(net "GND")
		)
		(pad "107" smd rect
			(at -2.050034 31.874968 90)
			(size 0.519938 1.4986)
			(layers "F.Cu" "F.Mask" "F.Paste")
			(net "M_A_CPU1_SB_DQ<4>")
		)
		(pad "108" smd rect
			(at -2.050034 32.725106 90)
			(size 0.519938 1.4986)
			(layers "F.Cu" "F.Mask" "F.Paste")
			(net "GND")
		)
		(pad "109" smd rect
			(at -2.050034 33.57499 90)
			(size 0.519938 1.4986)
			(layers "F.Cu" "F.Mask" "F.Paste")
			(net "M_A_CPU1_SB_DQ<5>")
		)
		(pad "110" smd rect
			(at -2.050034 34.425128 90)
			(size 0.519938 1.4986)
			(layers "F.Cu" "F.Mask" "F.Paste")
			(net "GND")
		)
		(pad "111" smd rect
			(at -2.050034 35.275012 90)
			(size 0.519938 1.4986)
			(layers "F.Cu" "F.Mask" "F.Paste")
			(net "M_A_CPU1_SB_DQ<8>")
		)
		(pad "112" smd rect
			(at -2.050034 36.124896 90)
			(size 0.519938 1.4986)
			(layers "F.Cu" "F.Mask" "F.Paste")
			(net "GND")
		)
		(pad "113" smd rect
			(at -2.050034 36.975034 90)
			(size 0.519938 1.4986)
			(layers "F.Cu" "F.Mask" "F.Paste")
			(net "M_A_CPU1_SB_DQ<9>")
		)
		(pad "114" smd rect
			(at -2.050034 37.824918 90)
			(size 0.519938 1.4986)
			(layers "F.Cu" "F.Mask" "F.Paste")
			(net "GND")
		)
		(pad "115" smd rect
			(at -2.050034 38.675056 90)
			(size 0.519938 1.4986)
			(layers "F.Cu" "F.Mask" "F.Paste")
			(net "M_A_CPU1_SB_DQS_DP<1>")
		)
		(pad "116" smd rect
			(at -2.050034 39.52494 90)
			(size 0.519938 1.4986)
			(layers "F.Cu" "F.Mask" "F.Paste")
			(net "M_A_CPU1_SB_DQS_DN<1>")
		)
		(pad "117" smd rect
			(at -2.050034 40.375078 90)
			(size 0.519938 1.4986)
			(layers "F.Cu" "F.Mask" "F.Paste")
			(net "GND")
		)
		(pad "118" smd rect
			(at -2.050034 41.224962 90)
			(size 0.519938 1.4986)
			(layers "F.Cu" "F.Mask" "F.Paste")
			(net "M_A_CPU1_SB_DQ<12>")
		)
		(pad "119" smd rect
			(at -2.050034 42.0751 90)
			(size 0.519938 1.4986)
			(layers "F.Cu" "F.Mask" "F.Paste")
			(net "GND")
		)
		(pad "120" smd rect
			(at -2.050034 42.924984 90)
			(size 0.519938 1.4986)
			(layers "F.Cu" "F.Mask" "F.Paste")
			(net "M_A_CPU1_SB_DQ<13>")
		)
		(pad "121" smd rect
			(at -2.050034 43.775122 90)
			(size 0.519938 1.4986)
			(layers "F.Cu" "F.Mask" "F.Paste")
			(net "GND")
		)
		(pad "122" smd rect
			(at -2.050034 44.625006 90)
			(size 0.519938 1.4986)
			(layers "F.Cu" "F.Mask" "F.Paste")
			(net "M_A_CPU1_SB_DQ<16>")
		)
		(pad "123" smd rect
			(at -2.050034 45.47489 90)
			(size 0.519938 1.4986)
			(layers "F.Cu" "F.Mask" "F.Paste")
			(net "GND")
		)
		(pad "124" smd rect
			(at -2.050034 46.325028 90)
			(size 0.519938 1.4986)
			(layers "F.Cu" "F.Mask" "F.Paste")
			(net "M_A_CPU1_SB_DQ<17>")
		)
		(pad "125" smd rect
			(at -2.050034 47.174912 90)
			(size 0.519938 1.4986)
			(layers "F.Cu" "F.Mask" "F.Paste")
			(net "GND")
		)
		(pad "126" smd rect
			(at -2.050034 48.02505 90)
			(size 0.519938 1.4986)
			(layers "F.Cu" "F.Mask" "F.Paste")
			(net "M_A_CPU1_SB_DQS_DP<2>")
		)
		(pad "127" smd rect
			(at -2.050034 48.874934 90)
			(size 0.519938 1.4986)
			(layers "F.Cu" "F.Mask" "F.Paste")
			(net "M_A_CPU1_SB_DQS_DN<2>")
		)
		(pad "128" smd rect
			(at -2.050034 49.725072 90)
			(size 0.519938 1.4986)
			(layers "F.Cu" "F.Mask" "F.Paste")
			(net "GND")
		)
		(pad "129" smd rect
			(at -2.050034 50.574956 90)
			(size 0.519938 1.4986)
			(layers "F.Cu" "F.Mask" "F.Paste")
			(net "M_A_CPU1_SB_DQ<20>")
		)
		(pad "130" smd rect
			(at -2.050034 51.425094 90)
			(size 0.519938 1.4986)
			(layers "F.Cu" "F.Mask" "F.Paste")
			(net "GND")
		)
		(pad "131" smd rect
			(at -2.050034 52.274978 90)
			(size 0.519938 1.4986)
			(layers "F.Cu" "F.Mask" "F.Paste")
			(net "M_A_CPU1_SB_DQ<21>")
		)
		(pad "132" smd rect
			(at -2.050034 53.125116 90)
			(size 0.519938 1.4986)
			(layers "F.Cu" "F.Mask" "F.Paste")
			(net "GND")
		)
		(pad "133" smd rect
			(at -2.050034 53.975 90)
			(size 0.519938 1.4986)
			(layers "F.Cu" "F.Mask" "F.Paste")
			(net "M_A_CPU1_SB_DQ<24>")
		)
		(pad "134" smd rect
			(at -2.050034 54.824884 90)
			(size 0.519938 1.4986)
			(layers "F.Cu" "F.Mask" "F.Paste")
			(net "GND")
		)
		(pad "135" smd rect
			(at -2.050034 55.675022 90)
			(size 0.519938 1.4986)
			(layers "F.Cu" "F.Mask" "F.Paste")
			(net "M_A_CPU1_SB_DQ<25>")
		)
		(pad "136" smd rect
			(at -2.050034 56.524906 90)
			(size 0.519938 1.4986)
			(layers "F.Cu" "F.Mask" "F.Paste")
			(net "GND")
		)
		(pad "137" smd rect
			(at -2.050034 57.375044 90)
			(size 0.519938 1.4986)
			(layers "F.Cu" "F.Mask" "F.Paste")
			(net "M_A_CPU1_SB_DQS_DP<3>")
		)
		(pad "138" smd rect
			(at -2.050034 58.224928 90)
			(size 0.519938 1.4986)
			(layers "F.Cu" "F.Mask" "F.Paste")
			(net "M_A_CPU1_SB_DQS_DN<3>")
		)
	)
)
